(kicad_pcb
	(version 20260206)
	(generator "pcbnew")
	(generator_version "10.0")
	(general
		(thickness 1.6)
		(legacy_teardrops no)
	)
	(paper "A4")
	(title_block
		(title "12092022_DA0F0TFB6D0_F0T_FAN_BOARD_MP5048_D_brd_v02_OCP.brd")
		(comment 1 "Grand Teton / footprints 851-855 of 924")
	)
	(layers
		(0 "F.Cu" signal "TOP")
		(4 "In1.Cu" signal "GND")
		(6 "In2.Cu" signal "IN1")
		(8 "In3.Cu" signal "IN2")
		(10 "In4.Cu" signal "GND1")
		(2 "B.Cu" signal "BOTTOM")
		(9 "F.Adhes" user "F.Adhesive")
		(11 "B.Adhes" user "B.Adhesive")
		(13 "F.Paste" user "Package Geometry/Pastemask Top")
		(15 "B.Paste" user "Package Geometry/Pastemask Bottom")
		(5 "F.SilkS" user "Ref Des/Silkscreen Top")
		(7 "B.SilkS" user "Ref Des/Silkscreen Bottom")
		(1 "F.Mask" user "Board Geometry/Soldermask Top")
		(3 "B.Mask" user "Board Geometry/Soldermask Bottom")
		(17 "Dwgs.User" user "User.Drawings")
		(19 "Cmts.User" user "User.Comments")
		(21 "Eco1.User" user "User.Eco1")
		(23 "Eco2.User" user "User.Eco2")
		(25 "Edge.Cuts" user "Board Geometry/Outline")
		(27 "Margin" user)
		(31 "F.CrtYd" user "Package Geometry/Place Bound Top")
		(29 "B.CrtYd" user "Package Geometry/Place Bound Bottom")
		(35 "F.Fab" user "Ref Des/Assembly Top")
		(33 "B.Fab" user "Ref Des/Assembly Bottom")
	)
	(footprint ""
		(layer "B.Cu")
		(at 34.666428 -253.021846 90)
		(property "Reference" "U395"
			(at -1.307846 -2.943098 270)
			(unlocked yes)
			(layer "B.SilkS")
			(effects
				(font
					(size 0.7874 0.5842)
					(thickness 0.1524)
				)
				(justify left mirror)
			)
		)
		(property "Value" ""
			(at 0 0 90)
			(layer "B.Fab")
			(effects
				(font
					(size 1.27 1.27)
				)
				(justify mirror)
			)
		)
		(duplicate_pad_numbers_are_jumpers no)
		(fp_line
			(start 1.3462 -1.1938)
			(end 1.3462 1.1684)
			(stroke
				(width 0.1524)
				(type default)
			)
			(layer "B.SilkS")
		)
		(fp_line
			(start -1.3462 -1.1938)
			(end 1.3462 -1.1938)
			(stroke
				(width 0.1524)
				(type default)
			)
			(layer "B.SilkS")
		)
		(fp_line
			(start 1.3462 1.1938)
			(end -1.3462 1.1938)
			(stroke
				(width 0.1524)
				(type default)
			)
			(layer "B.SilkS")
		)
		(fp_line
			(start -1.3462 1.1938)
			(end -1.3462 -1.1938)
			(stroke
				(width 0.1524)
				(type default)
			)
			(layer "B.SilkS")
		)
		(fp_poly
			(pts
				(xy 1.447038 -0.760476) (xy 2.052066 -0.457962) (xy 2.052066 -1.06299)
			)
			(stroke
				(width 0)
				(type default)
			)
			(fill yes)
			(layer "B.SilkS")
		)
		(fp_line
			(start 0.674878 -1.124966)
			(end 0.674878 1.124966)
			(stroke
				(width 0.1)
				(type default)
			)
			(layer "B.Fab")
		)
		(fp_line
			(start -0.674878 -1.124966)
			(end 0.674878 -1.124966)
			(stroke
				(width 0.1)
				(type default)
			)
			(layer "B.Fab")
		)
		(fp_line
			(start 0.674878 1.124966)
			(end -0.674878 1.124966)
			(stroke
				(width 0.1)
				(type default)
			)
			(layer "B.Fab")
		)
		(fp_line
			(start -0.674878 1.124966)
			(end -0.674878 -1.124966)
			(stroke
				(width 0.1)
				(type default)
			)
			(layer "B.Fab")
		)
		(fp_poly
			(pts
				(xy 1.447038 -0.760476) (xy 2.052066 -0.457962) (xy 2.052066 -1.06299)
			)
			(stroke
				(width 0)
				(type default)
			)
			(fill yes)
			(layer "B.Fab")
		)
		(pad "1" smd rect
			(at 0.899922 -0.750062 270)
			(size 0.6096 0.6096)
			(layers "B.Cu" "B.Mask" "B.Paste")
			(net "NC_U395_P1")
		)
		(pad "2" smd rect
			(at 0.899922 0 180)
			(size 0.4064 0.6096)
			(layers "B.Cu" "B.Mask" "B.Paste")
			(net "FAN_1_PRSNT_BUF_N")
		)
		(pad "3" smd rect
			(at 0.899922 0.750062 270)
			(size 0.6096 0.6096)
			(layers "B.Cu" "B.Mask" "B.Paste")
			(net "GND")
		)
		(pad "4" smd rect
			(at -0.899922 0.750062 270)
			(size 0.6096 0.6096)
			(layers "B.Cu" "B.Mask" "B.Paste")
			(net "FAN_1_PRESENT")
		)
		(pad "5" smd rect
			(at -0.899922 -0.750062 270)
			(size 0.6096 0.6096)
			(layers "B.Cu" "B.Mask" "B.Paste")
			(net "P3V3_AUX")
		)
	)
	(footprint ""
		(layer "B.Cu")
		(at 46.191932 -90.371168 -90)
		(property "Reference" "PD9"
			(at 4.874768 3.800602 270)
			(unlocked yes)
			(layer "B.SilkS")
			(effects
				(font
					(size 0.7874 0.5842)
					(thickness 0.1524)
				)
				(justify left mirror)
			)
		)
		(property "Value" ""
			(at 0 0 90)
			(layer "B.Fab")
			(effects
				(font
					(size 1.27 1.27)
				)
				(justify mirror)
			)
		)
		(duplicate_pad_numbers_are_jumpers no)
		(fp_line
			(start -5.334 3.109976)
			(end -4.8133 3.109976)
			(stroke
				(width 0.1524)
				(type default)
			)
			(layer "B.SilkS")
		)
		(fp_line
			(start -5.334 3.109976)
			(end -5.334 0)
			(stroke
				(width 0.1524)
				(type default)
			)
			(layer "B.SilkS")
		)
		(fp_line
			(start -5.207 3.109976)
			(end -5.207 -3.109976)
			(stroke
				(width 0.1524)
				(type default)
			)
			(layer "B.SilkS")
		)
		(fp_line
			(start -5.1308 3.109976)
			(end -5.1308 -3.109976)
			(stroke
				(width 0.1524)
				(type default)
			)
			(layer "B.SilkS")
		)
		(fp_line
			(start -5.0292 3.109976)
			(end -5.0292 -3.109976)
			(stroke
				(width 0.1524)
				(type default)
			)
			(layer "B.SilkS")
		)
		(fp_line
			(start -4.9276 3.109976)
			(end -4.9276 -3.109976)
			(stroke
				(width 0.1524)
				(type default)
			)
			(layer "B.SilkS")
		)
		(fp_line
			(start -4.826 3.109976)
			(end 4.826 3.109976)
			(stroke
				(width 0.1524)
				(type default)
			)
			(layer "B.SilkS")
		)
		(fp_line
			(start 4.826 3.109976)
			(end 4.826 0)
			(stroke
				(width 0.1524)
				(type default)
			)
			(layer "B.SilkS")
		)
		(fp_line
			(start -1.143 1.397)
			(end -1.143 -1.397)
			(stroke
				(width 0.1524)
				(type default)
			)
			(layer "B.SilkS")
		)
		(fp_line
			(start 1.016 1.016)
			(end -1.016 0)
			(stroke
				(width 0.1524)
				(type default)
			)
			(layer "B.SilkS")
		)
		(fp_line
			(start -5.334 0)
			(end -5.334 -3.109976)
			(stroke
				(width 0.1524)
				(type default)
			)
			(layer "B.SilkS")
		)
		(fp_line
			(start -4.826 0)
			(end -4.826 3.109976)
			(stroke
				(width 0.1524)
				(type default)
			)
			(layer "B.SilkS")
		)
		(fp_line
			(start -1.143 0)
			(end -1.8034 0)
			(stroke
				(width 0.1524)
				(type default)
			)
			(layer "B.SilkS")
		)
		(fp_line
			(start -1.143 0)
			(end 1.016 -1.016)
			(stroke
				(width 0.1524)
				(type default)
			)
			(layer "B.SilkS")
		)
		(fp_line
			(start 1.0922 0)
			(end 1.7018 0)
			(stroke
				(width 0.1524)
				(type default)
			)
			(layer "B.SilkS")
		)
		(fp_line
			(start 4.826 0)
			(end 4.826 -3.109976)
			(stroke
				(width 0.1524)
				(type default)
			)
			(layer "B.SilkS")
		)
		(fp_line
			(start 1.016 -1.016)
			(end 1.016 1.016)
			(stroke
				(width 0.1524)
				(type default)
			)
			(layer "B.SilkS")
		)
		(fp_line
			(start -4.826 -3.109976)
			(end -4.826 0)
			(stroke
				(width 0.1524)
				(type default)
			)
			(layer "B.SilkS")
		)
		(fp_line
			(start -4.8133 -3.109976)
			(end -5.3467 -3.109976)
			(stroke
				(width 0.1524)
				(type default)
			)
			(layer "B.SilkS")
		)
		(fp_line
			(start 4.826 -3.109976)
			(end -4.826 -3.109976)
			(stroke
				(width 0.1524)
				(type default)
			)
			(layer "B.SilkS")
		)
		(fp_line
			(start -3.554984 3.109976)
			(end 3.554984 3.109976)
			(stroke
				(width 0.1)
				(type default)
			)
			(layer "B.Fab")
		)
		(fp_line
			(start 3.554984 3.109976)
			(end 3.554984 -3.109976)
			(stroke
				(width 0.1)
				(type default)
			)
			(layer "B.Fab")
		)
		(fp_line
			(start -1.143 1.397)
			(end -1.143 -1.397)
			(stroke
				(width 0.1)
				(type default)
			)
			(layer "B.Fab")
		)
		(fp_line
			(start 1.016 1.016)
			(end -1.016 0)
			(stroke
				(width 0.1)
				(type default)
			)
			(layer "B.Fab")
		)
		(fp_line
			(start -1.143 0)
			(end -1.8034 0)
			(stroke
				(width 0.1)
				(type default)
			)
			(layer "B.Fab")
		)
		(fp_line
			(start -1.143 0)
			(end 1.016 -1.016)
			(stroke
				(width 0.1)
				(type default)
			)
			(layer "B.Fab")
		)
		(fp_line
			(start 1.0922 0)
			(end 1.7018 0)
			(stroke
				(width 0.1)
				(type default)
			)
			(layer "B.Fab")
		)
		(fp_line
			(start 1.016 -1.016)
			(end 1.016 1.016)
			(stroke
				(width 0.1)
				(type default)
			)
			(layer "B.Fab")
		)
		(fp_line
			(start -3.554984 -3.109976)
			(end -3.554984 3.109976)
			(stroke
				(width 0.1)
				(type default)
			)
			(layer "B.Fab")
		)
		(fp_line
			(start 3.554984 -3.109976)
			(end -3.554984 -3.109976)
			(stroke
				(width 0.1)
				(type default)
			)
			(layer "B.Fab")
		)
		(fp_text user "-"
			(at -6.682232 -1.210818 90)
			(unlocked yes)
			(layer "B.SilkS")
			(effects
				(font
					(size 1.905 1.4224)
					(thickness 0.1524)
				)
				(justify left mirror)
			)
		)
		(fp_text user "+"
			(at 4.747768 -1.718818 90)
			(unlocked yes)
			(layer "B.SilkS")
			(effects
				(font
					(size 1.905 1.4224)
					(thickness 0.1524)
				)
				(justify left mirror)
			)
		)
		(fp_text user "-"
			(at -6.6802 0.22225 90)
			(unlocked yes)
			(layer "B.Fab")
			(effects
				(font
					(size 1.905 1.4224)
					(thickness 0.1524)
				)
				(justify left mirror)
			)
		)
		(fp_text user "+"
			(at 4.5466 0.19685 90)
			(unlocked yes)
			(layer "B.Fab")
			(effects
				(font
					(size 1.905 1.4224)
					(thickness 0.1524)
				)
				(justify left mirror)
			)
		)
		(pad "A" smd rect
			(at 3.400044 0 270)
			(size 2.5146 3.302)
			(layers "B.Cu" "B.Mask" "B.Paste")
			(net "GND")
		)
		(pad "C" smd rect
			(at -3.400044 0 270)
			(size 2.5146 3.302)
			(layers "B.Cu" "B.Mask" "B.Paste")
			(net "P52V_FAN_2")
		)
	)
	(footprint ""
		(layer "B.Cu")
		(at 9.413494 -73.962768 90)
		(property "Reference" "PC2123"
			(at 0 0 90)
			(layer "B.SilkS")
			(hide yes)
			(effects
				(font
					(size 1.27 1.27)
				)
				(justify mirror)
			)
		)
		(property "Value" ""
			(at 0 0 90)
			(layer "B.Fab")
			(effects
				(font
					(size 1.27 1.27)
				)
				(justify mirror)
			)
		)
		(duplicate_pad_numbers_are_jumpers no)
		(fp_line
			(start 0.7874 -0.4064)
			(end -0.7874 -0.4064)
			(stroke
				(width 0.1524)
				(type default)
			)
			(layer "B.SilkS")
		)
		(fp_line
			(start -0.7874 -0.4064)
			(end -0.7874 0.4064)
			(stroke
				(width 0.1524)
				(type default)
			)
			(layer "B.SilkS")
		)
		(fp_line
			(start 0.7874 0.4064)
			(end 0.7874 -0.4064)
			(stroke
				(width 0.1524)
				(type default)
			)
			(layer "B.SilkS")
		)
		(fp_line
			(start -0.7874 0.4064)
			(end 0.7874 0.4064)
			(stroke
				(width 0.1524)
				(type default)
			)
			(layer "B.SilkS")
		)
		(fp_line
			(start 0.67945 -0.305054)
			(end 0.12065 -0.305054)
			(stroke
				(width 0.1)
				(type default)
			)
			(layer "B.Fab")
		)
		(fp_line
			(start 0.12065 -0.305054)
			(end 0.12065 -0.2794)
			(stroke
				(width 0.1)
				(type default)
			)
			(layer "B.Fab")
		)
		(fp_line
			(start -0.12065 -0.3048)
			(end -0.67945 -0.3048)
			(stroke
				(width 0.1)
				(type default)
			)
			(layer "B.Fab")
		)
		(fp_line
			(start -0.67945 -0.3048)
			(end -0.67945 0.3048)
			(stroke
				(width 0.1)
				(type default)
			)
			(layer "B.Fab")
		)
		(fp_line
			(start 0.12065 -0.2794)
			(end -0.12065 -0.2794)
			(stroke
				(width 0.1)
				(type default)
			)
			(layer "B.Fab")
		)
		(fp_line
			(start -0.12065 -0.2794)
			(end -0.12065 -0.3048)
			(stroke
				(width 0.1)
				(type default)
			)
			(layer "B.Fab")
		)
		(fp_line
			(start 0.12065 0.2794)
			(end 0.12065 0.3048)
			(stroke
				(width 0.1)
				(type default)
			)
			(layer "B.Fab")
		)
		(fp_line
			(start -0.120396 0.2794)
			(end 0.12065 0.2794)
			(stroke
				(width 0.1)
				(type default)
			)
			(layer "B.Fab")
		)
		(fp_line
			(start 0.67945 0.3048)
			(end 0.67945 -0.305054)
			(stroke
				(width 0.1)
				(type default)
			)
			(layer "B.Fab")
		)
		(fp_line
			(start 0.12065 0.3048)
			(end 0.67945 0.3048)
			(stroke
				(width 0.1)
				(type default)
			)
			(layer "B.Fab")
		)
		(fp_line
			(start -0.120396 0.3048)
			(end -0.120396 0.2794)
			(stroke
				(width 0.1)
				(type default)
			)
			(layer "B.Fab")
		)
		(fp_line
			(start -0.67945 0.3048)
			(end -0.120396 0.3048)
			(stroke
				(width 0.1)
				(type default)
			)
			(layer "B.Fab")
		)
		(pad "1" smd circle
			(at 0.40005 0 270)
			(size 0 0)
			(layers "B.Cu" "B.Mask" "B.Paste")
			(net "FAN_5_TEMP")
		)
		(pad "2" smd circle
			(at -0.40005 0 270)
			(size 0 0)
			(layers "B.Cu" "B.Mask" "B.Paste")
			(net "GND")
		)
	)
	(footprint ""
		(layer "B.Cu")
		(at 42.27068 -64.837056 -90)
		(property "Reference" "PC2121"
			(at 0 0 90)
			(layer "B.SilkS")
			(hide yes)
			(effects
				(font
					(size 1.27 1.27)
				)
				(justify mirror)
			)
		)
		(property "Value" ""
			(at 0 0 90)
			(layer "B.Fab")
			(effects
				(font
					(size 1.27 1.27)
				)
				(justify mirror)
			)
		)
		(duplicate_pad_numbers_are_jumpers no)
		(fp_line
			(start -0.7874 0.4064)
			(end 0.7874 0.4064)
			(stroke
				(width 0.1524)
				(type default)
			)
			(layer "B.SilkS")
		)
		(fp_line
			(start 0.7874 0.4064)
			(end 0.7874 -0.4064)
			(stroke
				(width 0.1524)
				(type default)
			)
			(layer "B.SilkS")
		)
		(fp_line
			(start -0.7874 -0.4064)
			(end -0.7874 0.4064)
			(stroke
				(width 0.1524)
				(type default)
			)
			(layer "B.SilkS")
		)
		(fp_line
			(start 0.7874 -0.4064)
			(end -0.7874 -0.4064)
			(stroke
				(width 0.1524)
				(type default)
			)
			(layer "B.SilkS")
		)
		(fp_line
			(start -0.67945 0.3048)
			(end -0.120396 0.3048)
			(stroke
				(width 0.1)
				(type default)
			)
			(layer "B.Fab")
		)
		(fp_line
			(start -0.120396 0.3048)
			(end -0.120396 0.2794)
			(stroke
				(width 0.1)
				(type default)
			)
			(layer "B.Fab")
		)
		(fp_line
			(start 0.12065 0.3048)
			(end 0.67945 0.3048)
			(stroke
				(width 0.1)
				(type default)
			)
			(layer "B.Fab")
		)
		(fp_line
			(start 0.67945 0.3048)
			(end 0.67945 -0.305054)
			(stroke
				(width 0.1)
				(type default)
			)
			(layer "B.Fab")
		)
		(fp_line
			(start -0.120396 0.2794)
			(end 0.12065 0.2794)
			(stroke
				(width 0.1)
				(type default)
			)
			(layer "B.Fab")
		)
		(fp_line
			(start 0.12065 0.2794)
			(end 0.12065 0.3048)
			(stroke
				(width 0.1)
				(type default)
			)
			(layer "B.Fab")
		)
		(fp_line
			(start -0.12065 -0.2794)
			(end -0.12065 -0.3048)
			(stroke
				(width 0.1)
				(type default)
			)
			(layer "B.Fab")
		)
		(fp_line
			(start 0.12065 -0.2794)
			(end -0.12065 -0.2794)
			(stroke
				(width 0.1)
				(type default)
			)
			(layer "B.Fab")
		)
		(fp_line
			(start -0.67945 -0.3048)
			(end -0.67945 0.3048)
			(stroke
				(width 0.1)
				(type default)
			)
			(layer "B.Fab")
		)
		(fp_line
			(start -0.12065 -0.3048)
			(end -0.67945 -0.3048)
			(stroke
				(width 0.1)
				(type default)
			)
			(layer "B.Fab")
		)
		(fp_line
			(start 0.12065 -0.305054)
			(end 0.12065 -0.2794)
			(stroke
				(width 0.1)
				(type default)
			)
			(layer "B.Fab")
		)
		(fp_line
			(start 0.67945 -0.305054)
			(end 0.12065 -0.305054)
			(stroke
				(width 0.1)
				(type default)
			)
			(layer "B.Fab")
		)
		(pad "1" smd circle
			(at 0.40005 0 90)
			(size 0 0)
			(layers "B.Cu" "B.Mask" "B.Paste")
			(net "FAN_3_TEMP")
		)
		(pad "2" smd circle
			(at -0.40005 0 90)
			(size 0 0)
			(layers "B.Cu" "B.Mask" "B.Paste")
			(net "GND")
		)
	)
	(footprint ""
		(layer "B.Cu")
		(at 37.719 -73.962768 90)
		(property "Reference" "PC2120"
			(at 0 0 90)
			(layer "B.SilkS")
			(hide yes)
			(effects
				(font
					(size 1.27 1.27)
				)
				(justify mirror)
			)
		)
		(property "Value" ""
			(at 0 0 90)
			(layer "B.Fab")
			(effects
				(font
					(size 1.27 1.27)
				)
				(justify mirror)
			)
		)
		(duplicate_pad_numbers_are_jumpers no)
		(fp_line
			(start 0.7874 -0.4064)
			(end -0.7874 -0.4064)
			(stroke
				(width 0.1524)
				(type default)
			)
			(layer "B.SilkS")
		)
		(fp_line
			(start -0.7874 -0.4064)
			(end -0.7874 0.4064)
			(stroke
				(width 0.1524)
				(type default)
			)
			(layer "B.SilkS")
		)
		(fp_line
			(start 0.7874 0.4064)
			(end 0.7874 -0.4064)
			(stroke
				(width 0.1524)
				(type default)
			)
			(layer "B.SilkS")
		)
		(fp_line
			(start -0.7874 0.4064)
			(end 0.7874 0.4064)
			(stroke
				(width 0.1524)
				(type default)
			)
			(layer "B.SilkS")
		)
		(fp_line
			(start 0.67945 -0.305054)
			(end 0.12065 -0.305054)
			(stroke
				(width 0.1)
				(type default)
			)
			(layer "B.Fab")
		)
		(fp_line
			(start 0.12065 -0.305054)
			(end 0.12065 -0.2794)
			(stroke
				(width 0.1)
				(type default)
			)
			(layer "B.Fab")
		)
		(fp_line
			(start -0.12065 -0.3048)
			(end -0.67945 -0.3048)
			(stroke
				(width 0.1)
				(type default)
			)
			(layer "B.Fab")
		)
		(fp_line
			(start -0.67945 -0.3048)
			(end -0.67945 0.3048)
			(stroke
				(width 0.1)
				(type default)
			)
			(layer "B.Fab")
		)
		(fp_line
			(start 0.12065 -0.2794)
			(end -0.12065 -0.2794)
			(stroke
				(width 0.1)
				(type default)
			)
			(layer "B.Fab")
		)
		(fp_line
			(start -0.12065 -0.2794)
			(end -0.12065 -0.3048)
			(stroke
				(width 0.1)
				(type default)
			)
			(layer "B.Fab")
		)
		(fp_line
			(start 0.12065 0.2794)
			(end 0.12065 0.3048)
			(stroke
				(width 0.1)
				(type default)
			)
			(layer "B.Fab")
		)
		(fp_line
			(start -0.120396 0.2794)
			(end 0.12065 0.2794)
			(stroke
				(width 0.1)
				(type default)
			)
			(layer "B.Fab")
		)
		(fp_line
			(start 0.67945 0.3048)
			(end 0.67945 -0.305054)
			(stroke
				(width 0.1)
				(type default)
			)
			(layer "B.Fab")
		)
		(fp_line
			(start 0.12065 0.3048)
			(end 0.67945 0.3048)
			(stroke
				(width 0.1)
				(type default)
			)
			(layer "B.Fab")
		)
		(fp_line
			(start -0.120396 0.3048)
			(end -0.120396 0.2794)
			(stroke
				(width 0.1)
				(type default)
			)
			(layer "B.Fab")
		)
		(fp_line
			(start -0.67945 0.3048)
			(end -0.120396 0.3048)
			(stroke
				(width 0.1)
				(type default)
			)
			(layer "B.Fab")
		)
		(pad "1" smd circle
			(at 0.40005 0 270)
			(size 0 0)
			(layers "B.Cu" "B.Mask" "B.Paste")
			(net "FAN_2_TEMP")
		)
		(pad "2" smd circle
			(at -0.40005 0 270)
			(size 0 0)
			(layers "B.Cu" "B.Mask" "B.Paste")
			(net "GND")
		)
	)
)
